(kicad_pcb
	(version 20241229)
	(generator "pcbnew")
	(generator_version "9.0")
	(general
		(thickness 1.599998)
		(legacy_teardrops no)
	)
	(paper "A4")
	(title_block
		(date "2023-02-12")
		(rev "1.1.5")
		(comment 9 "footprints 470-473 of 473")
	)
	(layers
		(0 "F.Cu" signal)
		(4 "In1.Cu" power "In1.GND")
		(6 "In2.Cu" signal)
		(8 "In3.Cu" power "In3.GND")
		(10 "In4.Cu" power "In4.VCC")
		(12 "In5.Cu" signal)
		(14 "In6.Cu" power "In6.VCC")
		(2 "B.Cu" signal)
		(9 "F.Adhes" user "F.Adhesive")
		(11 "B.Adhes" user "B.Adhesive")
		(13 "F.Paste" user)
		(15 "B.Paste" user)
		(5 "F.SilkS" user "F.Silkscreen")
		(7 "B.SilkS" user "B.Silkscreen")
		(1 "F.Mask" user)
		(3 "B.Mask" user)
		(17 "Dwgs.User" user "User.Drawings")
		(19 "Cmts.User" user "User.Comments")
		(21 "Eco1.User" user "User.Eco1")
		(23 "Eco2.User" user "User.Eco2")
		(25 "Edge.Cuts" user)
		(27 "Margin" user)
		(31 "F.CrtYd" user "F.Courtyard")
		(29 "B.CrtYd" user "B.Courtyard")
		(35 "F.Fab" user)
		(33 "B.Fab" user)
	)
	(footprint "antmicro-footprints:C_0402_1005Metric"
		(layer "B.Cu")
		(at 137.9 70.8 -90)
		(descr "Capacitor SMD 0402")
		(tags "capacitor SMD 0402")
		(property "Reference" "C199"
			(at -1.4 -1.2 90)
			(layer "B.SilkS")
			(effects
				(font
					(size 0.7 0.7)
					(thickness 0.15)
				)
				(justify left bottom mirror)
			)
		)
		(property "Value" "C_1n8_0402"
			(at 0 -1.4 90)
			(layer "B.Fab")
			(effects
				(font
					(size 0.7 0.7)
					(thickness 0.15)
				)
				(justify left bottom mirror)
			)
		)
		(property "Description" " "
			(at 0 0 270)
			(layer "F.Fab")
			(hide yes)
			(effects
				(font
					(size 1.27 1.27)
					(thickness 0.15)
				)
			)
		)
		(property "Author" "Antmicro"
			(at 67.1 208.7 0)
			(layer "B.Fab")
			(hide yes)
			(effects
				(font
					(size 1 1)
					(thickness 0.15)
				)
				(justify mirror)
			)
		)
		(property "Dielectric" ""
			(at 67.1 208.7 0)
			(layer "B.Fab")
			(hide yes)
			(effects
				(font
					(size 1 1)
					(thickness 0.15)
				)
				(justify mirror)
			)
		)
		(property "License" "Apache-2.0"
			(at 67.1 208.7 0)
			(layer "B.Fab")
			(hide yes)
			(effects
				(font
					(size 1 1)
					(thickness 0.15)
				)
				(justify mirror)
			)
		)
		(property "MPN" "0402B182K500CT"
			(at 67.1 208.7 0)
			(layer "B.Fab")
			(hide yes)
			(effects
				(font
					(size 1 1)
					(thickness 0.15)
				)
				(justify mirror)
			)
		)
		(property "Manufacturer" "Walsin"
			(at 67.1 208.7 0)
			(layer "B.Fab")
			(hide yes)
			(effects
				(font
					(size 1 1)
					(thickness 0.15)
				)
				(justify mirror)
			)
		)
		(property "Val" "1n8"
			(at 67.1 208.7 0)
			(layer "B.Fab")
			(hide yes)
			(effects
				(font
					(size 1 1)
					(thickness 0.15)
				)
				(justify mirror)
			)
		)
		(property "Voltage" ""
			(at 67.1 208.7 0)
			(layer "B.Fab")
			(hide yes)
			(effects
				(font
					(size 1 1)
					(thickness 0.15)
				)
				(justify mirror)
			)
		)
		(sheetname "Supply")
		(sheetfile "supply.kicad_sch")
		(attr exclude_from_pos_files exclude_from_bom dnp)
		(fp_rect
			(start -0.94 0.47)
			(end 0.94 -0.47)
			(stroke
				(width 0.05)
				(type solid)
			)
			(fill no)
			(layer "B.CrtYd")
		)
		(fp_rect
			(start -0.499 0.249)
			(end 0.499 -0.249)
			(stroke
				(width 0.15)
				(type solid)
			)
			(fill no)
			(layer "B.Fab")
		)
		(pad "1" smd roundrect
			(at -0.484 0 270)
			(size 0.59 0.64)
			(layers "B.Cu" "B.Mask" "B.Paste")
			(roundrect_rratio 0.25)
			(net 62 "Net-(U16-CAP)")
			(pintype "passive")
		)
		(pad "2" smd roundrect
			(at 0.484 0 270)
			(size 0.59 0.64)
			(layers "B.Cu" "B.Mask" "B.Paste")
			(roundrect_rratio 0.25)
			(net 5 "GND")
			(pintype "passive")
		)
	)
	(footprint "antmicro-footprints:RENESAS-TDFN-8-1.5x2.0mm_P0.5mm"
		(layer "B.Cu")
		(at 136.3 77.9)
		(descr "8 Lead TDFN Package 1.5 x 2.0 mm (Fused Lead) JEDEC MO-252 ")
		(property "Reference" "U15"
			(at -3.458 -1.192 180)
			(unlocked yes)
			(layer "B.SilkS")
			(effects
				(font
					(size 0.7 0.7)
					(thickness 0.15)
				)
				(justify left bottom mirror)
			)
		)
		(property "Value" "SLG59M1457V"
			(at -9.7 -2.4 180)
			(unlocked yes)
			(layer "B.Fab")
			(effects
				(font
					(size 0.7 0.7)
					(thickness 0.15)
				)
				(justify left bottom mirror)
			)
		)
		(property "Description" "Power distribution switch/load driver"
			(at 0 0 0)
			(layer "F.Fab")
			(hide yes)
			(effects
				(font
					(size 1.27 1.27)
					(thickness 0.15)
				)
			)
		)
		(property "Author" "Antmicro"
			(at 0 0 0)
			(layer "B.Fab")
			(hide yes)
			(effects
				(font
					(size 1 1)
					(thickness 0.15)
				)
				(justify mirror)
			)
		)
		(property "License" "Apache-2.0"
			(at 0 0 0)
			(layer "B.Fab")
			(hide yes)
			(effects
				(font
					(size 1 1)
					(thickness 0.15)
				)
				(justify mirror)
			)
		)
		(property "MPN" "SLG59M1457V"
			(at 0 0 0)
			(layer "B.Fab")
			(hide yes)
			(effects
				(font
					(size 1 1)
					(thickness 0.15)
				)
				(justify mirror)
			)
		)
		(property "Manufacturer" "Dialog Semiconductor"
			(at 0 0 0)
			(layer "B.Fab")
			(hide yes)
			(effects
				(font
					(size 1 1)
					(thickness 0.15)
				)
				(justify mirror)
			)
		)
		(sheetname "Supply")
		(sheetfile "supply.kicad_sch")
		(attr exclude_from_pos_files exclude_from_bom dnp)
		(fp_line
			(start -0.946 1.101)
			(end 0.498 1.101)
			(stroke
				(width 0.15)
				(type solid)
			)
			(layer "B.SilkS")
		)
		(fp_line
			(start -0.5 -1.1)
			(end 0.498 -1.1)
			(stroke
				(width 0.15)
				(type solid)
			)
			(layer "B.SilkS")
		)
		(fp_circle
			(center -1.3 0.75)
			(end -1.249 0.75)
			(stroke
				(width 0.15)
				(type solid)
			)
			(fill yes)
			(layer "B.SilkS")
		)
		(fp_rect
			(start -1.25 1.5)
			(end 1.248 -1.498)
			(stroke
				(width 0.05)
				(type solid)
			)
			(fill no)
			(layer "B.CrtYd")
		)
		(fp_line
			(start -0.777 -1.03)
			(end 0.785 -1.03)
			(stroke
				(width 0.15)
				(type solid)
			)
			(layer "B.Fab")
		)
		(fp_line
			(start -0.777 0.75)
			(end -0.777 -1.03)
			(stroke
				(width 0.15)
				(type solid)
			)
			(layer "B.Fab")
		)
		(fp_line
			(start -0.495 1.031)
			(end -0.777 0.75)
			(stroke
				(width 0.15)
				(type solid)
			)
			(layer "B.Fab")
		)
		(fp_line
			(start 0.785 1.031)
			(end -0.495 1.031)
			(stroke
				(width 0.15)
				(type solid)
			)
			(layer "B.Fab")
		)
		(fp_line
			(start 0.785 1.031)
			(end 0.785 -1.03)
			(stroke
				(width 0.15)
				(type solid)
			)
			(layer "B.Fab")
		)
		(pad "1" smd rect
			(at -0.527 0.75 90)
			(size 0.28 0.85)
			(layers "B.Cu" "B.Mask" "B.Paste")
			(net 459 "3V3_SYS")
			(pinfunction "VDD")
			(pintype "power_in")
		)
		(pad "2" smd rect
			(at -0.576 0.25 90)
			(size 0.28 0.75)
			(layers "B.Cu" "B.Mask" "B.Paste")
			(net 263 "Net-(U15-ON)")
			(pinfunction "ON")
			(pintype "input")
		)
		(pad "3" smd custom
			(at -0.576 -0.248 90)
			(size 0.28 0.75)
			(layers "B.Cu" "B.Mask" "B.Paste")
			(net 461 "1V1_SYS")
			(pinfunction "IN")
			(pintype "power_in")
			(zone_connect 2)
			(options
				(clearance outline)
				(anchor rect)
			)
			(primitives
				(gr_poly
					(pts
						(xy -0.14 0.375) (xy -0.14 -0.05) (xy 0.64 -0.05) (xy 0.64 0.375)
					)
					(width 0)
					(fill yes)
				)
				(gr_rect
					(start 0.36 -0.375)
					(end 0.64 0.375)
					(width 0)
					(fill yes)
				)
			)
		)
		(pad "5" smd custom
			(at 0.574 -0.748 270)
			(size 0.28 0.75)
			(layers "B.Cu" "B.Mask" "B.Paste")
			(net 273 "1V1_DDR")
			(pinfunction "OUT")
			(pintype "power_out")
			(zone_connect 2)
			(options
				(clearance outline)
				(anchor rect)
			)
			(primitives
				(gr_poly
					(pts
						(xy -0.14 0.375) (xy -0.14 -0.05) (xy 0.64 -0.05) (xy 0.64 0.375)
					)
					(width 0)
					(fill yes)
				)
				(gr_rect
					(start 0.36 -0.375)
					(end 0.64 0.375)
					(width 0)
					(fill yes)
				)
			)
		)
		(pad "7" smd rect
			(at 0.574 0.25 90)
			(size 0.28 0.75)
			(layers "B.Cu" "B.Mask" "B.Paste")
			(net 60 "Net-(U15-CAP)")
			(pinfunction "CAP")
			(pintype "input")
		)
		(pad "8" smd rect
			(at 0.574 0.75 90)
			(size 0.28 0.75)
			(layers "B.Cu" "B.Mask" "B.Paste")
			(net 5 "GND")
			(pinfunction "GND")
			(pintype "passive")
		)
	)
	(footprint "antmicro-footprints:SOT-23-3"
		(layer "B.Cu")
		(at 122.7 66.55 90)
		(property "Reference" "Q13"
			(at 1.15 -1.8 90)
			(layer "B.SilkS")
			(effects
				(font
					(size 0.7 0.7)
					(thickness 0.15)
				)
				(justify left bottom mirror)
			)
		)
		(property "Value" "BSS123"
			(at -1.9 -2.7 270)
			(layer "B.Fab")
			(effects
				(font
					(size 0.7 0.7)
					(thickness 0.15)
				)
				(justify left bottom mirror)
			)
		)
		(property "Author" "Antmicro"
			(at 189.25 -56.15 0)
			(layer "B.Fab")
			(hide yes)
			(effects
				(font
					(size 1 1)
					(thickness 0.15)
				)
				(justify mirror)
			)
		)
		(property "License" "Apache-2.0"
			(at 189.25 -56.15 0)
			(layer "B.Fab")
			(hide yes)
			(effects
				(font
					(size 1 1)
					(thickness 0.15)
				)
				(justify mirror)
			)
		)
		(property "MPN" "BSS123"
			(at 189.25 -56.15 0)
			(layer "B.Fab")
			(hide yes)
			(effects
				(font
					(size 1 1)
					(thickness 0.15)
				)
				(justify mirror)
			)
		)
		(property "Manufacturer" "ON Semiconductor"
			(at 189.25 -56.15 0)
			(layer "B.Fab")
			(hide yes)
			(effects
				(font
					(size 1 1)
					(thickness 0.15)
				)
				(justify mirror)
			)
		)
		(sheetname "Supply")
		(sheetfile "supply.kicad_sch")
		(attr exclude_from_pos_files exclude_from_bom dnp)
		(fp_line
			(start 0.7 -1.5)
			(end -0.7 -1.5)
			(stroke
				(width 0.15)
				(type solid)
			)
			(layer "B.SilkS")
		)
		(fp_line
			(start -0.7 -1.5)
			(end -0.7 -1.35)
			(stroke
				(width 0.15)
				(type solid)
			)
			(layer "B.SilkS")
		)
		(fp_line
			(start 0.7 -0.4)
			(end 0.7 -1.5)
			(stroke
				(width 0.15)
				(type solid)
			)
			(layer "B.SilkS")
		)
		(fp_line
			(start 0.7 0.4)
			(end 0.7 1.5)
			(stroke
				(width 0.15)
				(type solid)
			)
			(layer "B.SilkS")
		)
		(fp_line
			(start -0.85 1.35)
			(end -0.7 1.5)
			(stroke
				(width 0.15)
				(type solid)
			)
			(layer "B.SilkS")
		)
		(fp_line
			(start -1.45 1.35)
			(end -0.85 1.35)
			(stroke
				(width 0.15)
				(type solid)
			)
			(layer "B.SilkS")
		)
		(fp_line
			(start 0.7 1.5)
			(end -0.7 1.5)
			(stroke
				(width 0.15)
				(type solid)
			)
			(layer "B.SilkS")
		)
		(fp_line
			(start 0.85 -1.65)
			(end -0.85 -1.65)
			(stroke
				(width 0.05)
				(type solid)
			)
			(layer "B.CrtYd")
		)
		(fp_line
			(start -0.85 -1.65)
			(end -0.85 -1.4)
			(stroke
				(width 0.05)
				(type solid)
			)
			(layer "B.CrtYd")
		)
		(fp_line
			(start -0.85 -1.4)
			(end -1.75 -1.4)
			(stroke
				(width 0.05)
				(type solid)
			)
			(layer "B.CrtYd")
		)
		(fp_line
			(start -1.75 -1.4)
			(end -1.75 -0.5)
			(stroke
				(width 0.05)
				(type solid)
			)
			(layer "B.CrtYd")
		)
		(fp_line
			(start -0.85 -0.5)
			(end -0.85 0.5)
			(stroke
				(width 0.05)
				(type solid)
			)
			(layer "B.CrtYd")
		)
		(fp_line
			(start -1.75 -0.5)
			(end -0.85 -0.5)
			(stroke
				(width 0.05)
				(type solid)
			)
			(layer "B.CrtYd")
		)
		(fp_line
			(start 1.75 -0.45)
			(end 0.85 -0.45)
			(stroke
				(width 0.05)
				(type solid)
			)
			(layer "B.CrtYd")
		)
		(fp_line
			(start 0.85 -0.45)
			(end 0.85 -1.65)
			(stroke
				(width 0.05)
				(type solid)
			)
			(layer "B.CrtYd")
		)
		(fp_line
			(start 1.75 0.45)
			(end 1.75 -0.45)
			(stroke
				(width 0.05)
				(type solid)
			)
			(layer "B.CrtYd")
		)
		(fp_line
			(start 0.825 0.45)
			(end 1.75 0.45)
			(stroke
				(width 0.05)
				(type solid)
			)
			(layer "B.CrtYd")
		)
		(fp_line
			(start -0.85 0.5)
			(end -1.75 0.5)
			(stroke
				(width 0.05)
				(type solid)
			)
			(layer "B.CrtYd")
		)
		(fp_line
			(start -1.75 0.5)
			(end -1.75 1.4)
			(stroke
				(width 0.05)
				(type solid)
			)
			(layer "B.CrtYd")
		)
		(fp_line
			(start -0.9 1.4)
			(end -1.75 1.4)
			(stroke
				(width 0.05)
				(type solid)
			)
			(layer "B.CrtYd")
		)
		(fp_line
			(start 0.825 1.6)
			(end 0.825 0.45)
			(stroke
				(width 0.05)
				(type solid)
			)
			(layer "B.CrtYd")
		)
		(fp_line
			(start -0.9 1.6)
			(end -0.9 1.4)
			(stroke
				(width 0.05)
				(type solid)
			)
			(layer "B.CrtYd")
		)
		(fp_line
			(start -0.9 1.6)
			(end 0.825 1.6)
			(stroke
				(width 0.05)
				(type solid)
			)
			(layer "B.CrtYd")
		)
		(fp_line
			(start 0.688 -1.519)
			(end 0.688 1.52)
			(stroke
				(width 0.15)
				(type solid)
			)
			(layer "B.Fab")
		)
		(fp_line
			(start -0.712 -1.519)
			(end 0.688 -1.519)
			(stroke
				(width 0.15)
				(type solid)
			)
			(layer "B.Fab")
		)
		(fp_line
			(start -0.712 1.325)
			(end -0.712 -1.523)
			(stroke
				(width 0.15)
				(type solid)
			)
			(layer "B.Fab")
		)
		(fp_line
			(start -0.437 1.526)
			(end -0.712 1.325)
			(stroke
				(width 0.15)
				(type solid)
			)
			(layer "B.Fab")
		)
		(fp_line
			(start -0.437 1.526)
			(end 0.688 1.526)
			(stroke
				(width 0.15)
				(type solid)
			)
			(layer "B.Fab")
		)
		(pad "1" smd roundrect
			(at -1.1 0.951 90)
			(size 1 0.6)
			(layers "B.Cu" "B.Mask" "B.Paste")
			(roundrect_rratio 0.15)
			(net 238 "Net-(Q13-G)")
			(pinfunction "G")
			(pintype "bidirectional")
		)
		(pad "2" smd roundrect
			(at -1.1 -0.949 90)
			(size 1 0.6)
			(layers "B.Cu" "B.Mask" "B.Paste")
			(roundrect_rratio 0.15)
			(net 5 "GND")
			(pinfunction "S")
			(pintype "bidirectional")
		)
		(pad "3" smd roundrect
			(at 1.1 0.0005 90)
			(size 1 0.6)
			(layers "B.Cu" "B.Mask" "B.Paste")
			(roundrect_rratio 0.15)
			(net 636 "/Supply/0V6_EN")
			(pinfunction "D")
			(pintype "bidirectional")
		)
	)
	(footprint "antmicro-footprints:C_0603_1608Metric"
		(layer "B.Cu")
		(at 154.15 66.5 90)
		(descr "Capacitor SMD 0603")
		(tags "capacitor 0603")
		(property "Reference" "C150"
			(at 1.3 1.35 270)
			(layer "B.SilkS")
			(effects
				(font
					(size 0.7 0.7)
					(thickness 0.15)
				)
				(justify left bottom mirror)
			)
		)
		(property "Value" "C_10n_0603"
			(at 0 -1.6 270)
			(layer "B.Fab")
			(effects
				(font
					(size 0.7 0.7)
					(thickness 0.15)
				)
				(justify left bottom mirror)
			)
		)
		(property "Description" " "
			(at 0 0 90)
			(layer "F.Fab")
			(hide yes)
			(effects
				(font
					(size 1.27 1.27)
					(thickness 0.15)
				)
			)
		)
		(property "Author" "Antmicro"
			(at 220.65 -87.65 0)
			(layer "B.Fab")
			(hide yes)
			(effects
				(font
					(size 1 1)
					(thickness 0.15)
				)
				(justify mirror)
			)
		)
		(property "Dielectric" ""
			(at 220.65 -87.65 0)
			(layer "B.Fab")
			(hide yes)
			(effects
				(font
					(size 1 1)
					(thickness 0.15)
				)
				(justify mirror)
			)
		)
		(property "License" "Apache-2.0"
			(at 220.65 -87.65 0)
			(layer "B.Fab")
			(hide yes)
			(effects
				(font
					(size 1 1)
					(thickness 0.15)
				)
				(justify mirror)
			)
		)
		(property "MPN" "06031C103JAT2A"
			(at 220.65 -87.65 0)
			(layer "B.Fab")
			(hide yes)
			(effects
				(font
					(size 1 1)
					(thickness 0.15)
				)
				(justify mirror)
			)
		)
		(property "Manufacturer" "AVX"
			(at 220.65 -87.65 0)
			(layer "B.Fab")
			(hide yes)
			(effects
				(font
					(size 1 1)
					(thickness 0.15)
				)
				(justify mirror)
			)
		)
		(property "Val" "10n"
			(at 220.65 -87.65 0)
			(layer "B.Fab")
			(hide yes)
			(effects
				(font
					(size 1 1)
					(thickness 0.15)
				)
				(justify mirror)
			)
		)
		(property "Voltage" ""
			(at 220.65 -87.65 0)
			(layer "B.Fab")
			(hide yes)
			(effects
				(font
					(size 1 1)
					(thickness 0.15)
				)
				(justify mirror)
			)
		)
		(sheetname "Supply")
		(sheetfile "supply.kicad_sch")
		(attr smd)
		(fp_line
			(start -0.3 -0.3)
			(end 0.3 -0.3)
			(stroke
				(width 0.15)
				(type solid)
			)
			(layer "B.SilkS")
		)
		(fp_line
			(start -0.3 0.3)
			(end 0.3 0.3)
			(stroke
				(width 0.15)
				(type solid)
			)
			(layer "B.SilkS")
		)
		(fp_rect
			(start -1.24 0.7)
			(end 1.24 -0.7)
			(stroke
				(width 0.05)
				(type solid)
			)
			(fill no)
			(layer "B.CrtYd")
		)
		(fp_rect
			(start -0.8 0.4)
			(end 0.8 -0.4)
			(stroke
				(width 0.15)
				(type solid)
			)
			(fill no)
			(layer "B.Fab")
		)
		(pad "1" smd roundrect
			(at -0.7 0 90)
			(size 0.6 0.8)
			(layers "B.Cu" "B.Mask" "B.Paste")
			(roundrect_rratio 0.2)
			(net 641 "1V8_DDR")
			(pintype "passive")
		)
		(pad "2" smd roundrect
			(at 0.7 0 90)
			(size 0.6 0.8)
			(layers "B.Cu" "B.Mask" "B.Paste")
			(roundrect_rratio 0.2)
			(net 5 "GND")
			(pintype "passive")
		)
	)
)
